(kicad_pcb
	(version 20221018)
	(generator pcbnew)
	(general
    (thickness 1.7403)
  )
	(paper "A4")
	(title_block
    (title "Data Center RDIMM DDR4 Tester")
    (date "2024-09-30")
    (rev "1.2.4")
		(comment 9 "footprints 28-36 of 690")
	)
	(layers
    (0 "F.Cu" signal)
    (1 "In1.Cu" power)
    (2 "In2.Cu" signal)
    (3 "In3.Cu" power)
    (4 "In4.Cu" power)
    (5 "In5.Cu" signal)
    (6 "In6.Cu" power)
    (7 "In7.Cu" signal)
    (8 "In8.Cu" power)
    (9 "In9.Cu" signal)
    (10 "In10.Cu" power)
    (31 "B.Cu" signal)
    (32 "B.Adhes" user "B.Adhesive")
    (33 "F.Adhes" user "F.Adhesive")
    (34 "B.Paste" user)
    (35 "F.Paste" user)
    (36 "B.SilkS" user "B.Silkscreen")
    (37 "F.SilkS" user "F.Silkscreen")
    (38 "B.Mask" user)
    (39 "F.Mask" user)
    (40 "Dwgs.User" user "User.Drawings")
    (41 "Cmts.User" user "User.Comments")
    (42 "Eco1.User" user "User.Eco1")
    (43 "Eco2.User" user "User.Eco2")
    (44 "Edge.Cuts" user)
    (45 "Margin" user)
    (46 "B.CrtYd" user "B.Courtyard")
    (47 "F.CrtYd" user "F.Courtyard")
    (48 "B.Fab" user)
    (49 "F.Fab" user)
  )
	(footprint "data-center-rdimm-ddr4-tester-footprints:BarrelJack_3167288_Horizontal" (layer "F.Cu")
    (at 118.35 124.3)
    (property "Author" "Antmicro")
    (property "License" "Apache-2.0")
    (property "MPN" "MJ-179PH")
    (property "Manufacturer" "Multicomp Pro")
    (property "Sheetfile" "supply.kicad_sch")
    (property "Sheetname" "Supply")
    (property "ki_description" "DC Power Connector, Jack, 4 A, 1.95 mm, PCB Mount, Through Hole")
    (property "ki_keywords" "HORIZONTAL, THT, JACK, CONNECTOR, POWER")
    (attr through_hole)
    (fp_text reference "J3" (at 0 -1.4) (layer "F.SilkS")
        (effects (font (size 0.7 0.7) (thickness 0.15)) (justify left bottom))
    )
    (fp_text value "BarrelJack_3167288" (at 0 15.4) (layer "F.Fab")
        (effects (font (size 0.7 0.7) (thickness 0.15)) (justify left bottom))
    )
    (fp_text user "License: Apache-2.0" (at -5.1 18.802) (layer "F.Fab") hide
        (effects (font (size 0.7 0.7) (thickness 0.15)) (justify left bottom))
    )
    (fp_text user "${REFERENCE}" (at -5.1 16.4) (layer "F.Fab") hide
        (effects (font (size 0.7 0.7) (thickness 0.15)) (justify left bottom))
    )
    (fp_text user "Author: Antmicro" (at -5.1 17.601) (layer "F.Fab") hide
        (effects (font (size 0.7 0.7) (thickness 0.15)) (justify left bottom))
    )
    (fp_line (start -4.8 -0.1) (end -2.4 -0.1)
      (stroke (width 0.15) (type solid)) (layer "F.SilkS"))
    (fp_line (start -4.8 10.1) (end 4.8 10.1)
      (stroke (width 0.15) (type solid)) (layer "F.SilkS"))
    (fp_line (start -4.8 14) (end -4.8 -0.1)
      (stroke (width 0.15) (type solid)) (layer "F.SilkS"))
    (fp_line (start -4.8 14) (end 4.8 14)
      (stroke (width 0.15) (type solid)) (layer "F.SilkS"))
    (fp_line (start 2.4 -0.1) (end 4.8 -0.1)
      (stroke (width 0.15) (type solid)) (layer "F.SilkS"))
    (fp_line (start 4.8 -0.1) (end 4.8 0.8255)
      (stroke (width 0.15) (type solid)) (layer "F.SilkS"))
    (fp_line (start 4.8 14) (end 4.8 5.1)
      (stroke (width 0.15) (type solid)) (layer "F.SilkS"))
    (fp_line (start -5.1 -0.4) (end -5.1 14.3)
      (stroke (width 0.05) (type solid)) (layer "F.CrtYd"))
    (fp_line (start -5.1 14.3) (end 5.1 14.3)
      (stroke (width 0.05) (type solid)) (layer "F.CrtYd"))
    (fp_line (start -2.5 -1.3) (end -2.5 -0.4)
      (stroke (width 0.05) (type solid)) (layer "F.CrtYd"))
    (fp_line (start -2.5 -0.4) (end -5.1 -0.4)
      (stroke (width 0.05) (type solid)) (layer "F.CrtYd"))
    (fp_line (start 2.5 -1.3) (end -2.5 -1.3)
      (stroke (width 0.05) (type solid)) (layer "F.CrtYd"))
    (fp_line (start 2.5 -0.4) (end 2.5 -1.3)
      (stroke (width 0.05) (type solid)) (layer "F.CrtYd"))
    (fp_line (start 5.1 -0.4) (end 2.5 -0.4)
      (stroke (width 0.05) (type solid)) (layer "F.CrtYd"))
    (fp_line (start 5.1 0.7) (end 5.1 -0.4)
      (stroke (width 0.05) (type solid)) (layer "F.CrtYd"))
    (fp_line (start 5.1 5.2) (end 6.1 5.2)
      (stroke (width 0.05) (type solid)) (layer "F.CrtYd"))
    (fp_line (start 5.1 14.3) (end 5.1 5.2)
      (stroke (width 0.05) (type solid)) (layer "F.CrtYd"))
    (fp_line (start 6.1 0.7) (end 5.1 0.7)
      (stroke (width 0.05) (type solid)) (layer "F.CrtYd"))
    (fp_line (start 6.1 5.2) (end 6.1 0.7)
      (stroke (width 0.05) (type solid)) (layer "F.CrtYd"))
    (fp_line (start -3.6 -0.4) (end -4.5 0.5)
      (stroke (width 0.15) (type solid)) (layer "F.Fab"))
    (fp_rect (start -4.5 -0.4) (end 5.111 13.7)
      (stroke (width 0.15) (type solid)) (fill none) (layer "F.Fab"))
    (pad "1" thru_hole oval (at 0 0 270) (size 2 4.5) (drill oval 1 3.5) (layers "*.Cu" "*.Mask")
      (net 626 "VIN_RAW") (pinfunction "1") (pintype "passive"))
    (pad "2" thru_hole oval (at 4.879 2.948 180) (size 1.99 4) (drill oval 1 3) (layers "*.Cu" "*.Mask")
      (net 9 "GND") (pinfunction "2") (pintype "passive"))
    (pad "3" thru_hole oval (at 0 5.999 90) (size 2 4) (drill oval 1 3) (layers "*.Cu" "*.Mask")
      (net 9 "GND") (pinfunction "3") (pintype "passive"))
  )
	(footprint "data-center-rdimm-ddr4-tester-footprints:C_0603_1608Metric" (layer "F.Cu")
    (at 119.536328 102.497157)
    (descr "Capacitor SMD 0603")
    (tags "capacitor 0603")
    (property "Author" "Antmicro")
    (property "Dielectric" "")
    (property "License" "Apache-2.0")
    (property "MPN" "C1608X5R1E106M080AC")
    (property "Manufacturer" "TDK")
    (property "Sheetfile" "supply.kicad_sch")
    (property "Sheetname" "Supply")
    (property "Val" "10u/25V")
    (property "Voltage" "")
    (property "ki_description" " ")
    (attr smd)
    (fp_text reference "C27" (at -1.156328 -0.467157) (layer "F.SilkS")
        (effects (font (size 0.7 0.7) (thickness 0.15)) (justify left bottom))
    )
    (fp_text value "C_10u_25V_0603" (at 0 1.6) (layer "F.Fab") hide
        (effects (font (size 0.7 0.7) (thickness 0.15)) (justify left bottom))
    )
    (fp_text user "${REFERENCE}" (at -1.682 3.895) (layer "F.Fab") hide
        (effects (font (size 0.7 0.7) (thickness 0.15)) (justify left bottom))
    )
    (fp_text user "Author: Antmicro" (at -1.682 4.894) (layer "F.Fab") hide
        (effects (font (size 0.7 0.7) (thickness 0.15)) (justify left bottom))
    )
    (fp_text user "License: Apache-2.0" (at -1.682 5.895) (layer "F.Fab") hide
        (effects (font (size 0.7 0.7) (thickness 0.15)) (justify left bottom))
    )
    (fp_line (start -0.3 -0.3) (end 0.3 -0.3)
      (stroke (width 0.15) (type solid)) (layer "F.SilkS"))
    (fp_line (start -0.3 0.3) (end 0.3 0.3)
      (stroke (width 0.15) (type solid)) (layer "F.SilkS"))
    (fp_rect (start -1.24 -0.7) (end 1.24 0.7)
      (stroke (width 0.05) (type solid)) (fill none) (layer "F.CrtYd"))
    (fp_rect (start -0.8 -0.4) (end 0.8 0.4)
      (stroke (width 0.15) (type solid)) (fill none) (layer "F.Fab"))
    (pad "1" smd roundrect (at -0.7 0) (size 0.6 0.8) (layers "F.Cu" "F.Paste" "F.Mask") (roundrect_rratio 0.2)
      (net 103 "VIN") (pintype "passive"))
    (pad "2" smd roundrect (at 0.7 0) (size 0.6 0.8) (layers "F.Cu" "F.Paste" "F.Mask") (roundrect_rratio 0.2)
      (net 9 "GND") (pintype "passive"))
  )
	(footprint "data-center-rdimm-ddr4-tester-footprints:C_0402_1005Metric" (layer "F.Cu")
    (at 117.911328 114.997157 90)
    (descr "Capacitor SMD 0402")
    (tags "capacitor SMD 0402")
    (property "Author" "Antmicro")
    (property "Dielectric" "C0G")
    (property "License" "Apache-2.0")
    (property "MPN" "GRM1555C1E470JA01D")
    (property "Manufacturer" "Murata")
    (property "Sheetfile" "supply.kicad_sch")
    (property "Sheetname" "Supply")
    (property "Val" "47p")
    (property "Voltage" "")
    (property "ki_description" " ")
    (attr smd)
    (fp_text reference "C175" (at -4.492843 -3.621328 90) (layer "F.SilkS")
        (effects (font (size 0.7 0.7) (thickness 0.15)) (justify left bottom))
    )
    (fp_text value "C_47p_0402" (at 0 1.4 90) (layer "F.Fab") hide
        (effects (font (size 0.7 0.7) (thickness 0.15)) (justify left bottom))
    )
    (fp_text user "${REFERENCE}" (at -0.932 3.168 90) (layer "F.Fab") hide
        (effects (font (size 0.7 0.7) (thickness 0.15)) (justify left bottom))
    )
    (fp_text user "Author: Antmicro" (at -0.932 4.17 90) (layer "F.Fab") hide
        (effects (font (size 0.7 0.7) (thickness 0.15)) (justify left bottom))
    )
    (fp_text user "License: Apache-2.0" (at -0.932 5.17 90) (layer "F.Fab") hide
        (effects (font (size 0.7 0.7) (thickness 0.15)) (justify left bottom))
    )
    (fp_rect (start -0.94 -0.47) (end 0.94 0.47)
      (stroke (width 0.05) (type solid)) (fill none) (layer "F.CrtYd"))
    (fp_rect (start -0.499 -0.249) (end 0.499 0.249)
      (stroke (width 0.15) (type solid)) (fill none) (layer "F.Fab"))
    (pad "1" smd roundrect (at -0.484 0 90) (size 0.59 0.64) (layers "F.Cu" "F.Paste" "F.Mask") (roundrect_rratio 0.25)
      (net 69 "Net-(IC1-COMP)") (pintype "passive"))
    (pad "2" smd roundrect (at 0.484 0 90) (size 0.59 0.64) (layers "F.Cu" "F.Paste" "F.Mask") (roundrect_rratio 0.25)
      (net 9 "GND") (pintype "passive"))
  )
	(footprint "data-center-rdimm-ddr4-tester-footprints:C_0402_1005Metric" (layer "F.Cu")
    (at 115.661328 100.747157 180)
    (descr "Capacitor SMD 0402")
    (tags "capacitor SMD 0402")
    (property "Author" "Antmicro")
    (property "Dielectric" "")
    (property "License" "Apache-2.0")
    (property "MPN" "C1005X5R1E474M050BB")
    (property "Manufacturer" "TDK")
    (property "Sheetfile" "supply.kicad_sch")
    (property "Sheetname" "Supply")
    (property "Val" "470n")
    (property "Voltage" "")
    (property "ki_description" " ")
    (attr smd)
    (fp_text reference "C36" (at 0.091328 -1.212843) (layer "F.SilkS")
        (effects (font (size 0.7 0.7) (thickness 0.15)) (justify left bottom))
    )
    (fp_text value "C_470n_0402" (at 0 1.4 180) (layer "F.Fab") hide
        (effects (font (size 0.7 0.7) (thickness 0.15)) (justify left bottom))
    )
    (fp_text user "${REFERENCE}" (at -0.932 3.168 180) (layer "F.Fab") hide
        (effects (font (size 0.7 0.7) (thickness 0.15)) (justify left bottom))
    )
    (fp_text user "Author: Antmicro" (at -0.932 4.17 180) (layer "F.Fab") hide
        (effects (font (size 0.7 0.7) (thickness 0.15)) (justify left bottom))
    )
    (fp_text user "License: Apache-2.0" (at -0.932 5.17 180) (layer "F.Fab") hide
        (effects (font (size 0.7 0.7) (thickness 0.15)) (justify left bottom))
    )
    (fp_rect (start -0.94 -0.47) (end 0.94 0.47)
      (stroke (width 0.05) (type solid)) (fill none) (layer "F.CrtYd"))
    (fp_rect (start -0.499 -0.249) (end 0.499 0.249)
      (stroke (width 0.15) (type solid)) (fill none) (layer "F.Fab"))
    (pad "1" smd roundrect (at -0.484 0 180) (size 0.59 0.64) (layers "F.Cu" "F.Paste" "F.Mask") (roundrect_rratio 0.25)
      (net 305 "/Supply/VTTREF") (pintype "passive"))
    (pad "2" smd roundrect (at 0.484 0 180) (size 0.59 0.64) (layers "F.Cu" "F.Paste" "F.Mask") (roundrect_rratio 0.25)
      (net 9 "GND") (pintype "passive"))
  )
	(footprint "data-center-rdimm-ddr4-tester-footprints:Testpoint_smd_1mm" (layer "F.Cu")
    (at 109.287128 113.610008 90)
    (property "Author" "Antmicro")
    (property "License" "Apache-2.0")
    (property "MPN" "")
    (property "Manufacturer" "")
    (property "Sheetfile" "supply.kicad_sch")
    (property "Sheetname" "Supply")
    (property "ki_description" "Test Point 1mm")
    (attr exclude_from_pos_files)
    (fp_text reference "TP9" (at -0.809992 -0.637128 90) (layer "F.SilkS")
        (effects (font (size 0.7 0.7) (thickness 0.15)) (justify left bottom))
    )
    (fp_text value "TP_1mm_SMD" (at 0 1.4 90) (layer "F.Fab") hide
        (effects (font (size 0.7 0.7) (thickness 0.15)) (justify left bottom))
    )
    (fp_text user "Author: Antmicro" (at -0.5 4 90) (layer "F.Fab") hide
        (effects (font (size 0.7 0.7) (thickness 0.15)) (justify left bottom))
    )
    (fp_text user "License: Apache-2.0" (at -0.5 5.2 90) (layer "F.Fab") hide
        (effects (font (size 0.7 0.7) (thickness 0.15)) (justify left bottom))
    )
    (fp_text user "${REFERENCE}" (at -0.5 2.8 90) (layer "F.Fab") hide
        (effects (font (size 0.7 0.7) (thickness 0.15)) (justify left bottom))
    )
    (pad "1" smd circle (at 0 0 90) (size 1 1) (layers "F.Cu" "F.Mask")
      (net 167 "/Supply/SYS_EN") (pinfunction "1") (pintype "passive"))
  )
	(footprint "data-center-rdimm-ddr4-tester-footprints:R_0402_1005Metric" (layer "F.Cu")
    (at 118.411328 117.747157)
    (descr "Resistor SMD 0402")
    (tags "resistor SMD 0402")
    (property "Author" "Antmicro")
    (property "License" "Apache-2.0")
    (property "MPN" "CR0402-FX-1022GLF")
    (property "Manufacturer" "Bourns")
    (property "Sheetfile" "supply.kicad_sch")
    (property "Sheetname" "Supply")
    (property "Tolerance" "1%")
    (property "Val" "10k2")
    (property "ki_description" "10k2 resistor in 0402 package with 1% tolerance")
    (attr smd)
    (fp_text reference "R128" (at -5.171328 3.382843) (layer "F.SilkS")
        (effects (font (size 0.7 0.7) (thickness 0.15)) (justify left bottom))
    )
    (fp_text value "R_10k2_0402" (at 0 1.4) (layer "F.Fab") hide
        (effects (font (size 0.7 0.7) (thickness 0.15)) (justify left bottom))
    )
    (fp_text user "License: Apache-2.0" (at -0.95 5.169) (layer "F.Fab") hide
        (effects (font (size 0.7 0.7) (thickness 0.15)) (justify left bottom))
    )
    (fp_text user "${REFERENCE}" (at -0.95 3.168) (layer "F.Fab") hide
        (effects (font (size 0.7 0.7) (thickness 0.15)) (justify left bottom))
    )
    (fp_text user "Author: Antmicro" (at -0.95 4.169) (layer "F.Fab") hide
        (effects (font (size 0.7 0.7) (thickness 0.15)) (justify left bottom))
    )
    (fp_rect (start -0.93 -0.47) (end 0.93 0.47)
      (stroke (width 0.05) (type solid)) (fill none) (layer "F.CrtYd"))
    (fp_rect (start -0.5 -0.25) (end 0.5 0.25)
      (stroke (width 0.15) (type solid)) (fill none) (layer "F.Fab"))
    (pad "1" smd roundrect (at -0.485 0) (size 0.59 0.64) (layers "F.Cu" "F.Paste" "F.Mask") (roundrect_rratio 0.25)
      (net 110 "Net-(IC1-FB)") (pintype "passive"))
    (pad "2" smd roundrect (at 0.485 0) (size 0.59 0.64) (layers "F.Cu" "F.Paste" "F.Mask") (roundrect_rratio 0.25)
      (net 9 "GND") (pintype "passive"))
  )
	(footprint "data-center-rdimm-ddr4-tester-footprints:Testpoint_smd_1mm" (layer "F.Cu")
    (at 135 101.125)
    (property "Author" "Antmicro")
    (property "License" "Apache-2.0")
    (property "MPN" "")
    (property "Manufacturer" "")
    (property "Sheetfile" "supply.kicad_sch")
    (property "Sheetname" "Supply")
    (property "ki_description" "Test Point 1mm")
    (attr exclude_from_pos_files)
    (fp_text reference "3V3" (at -1.06 -0.615) (layer "F.SilkS")
        (effects (font (size 0.7 0.7) (thickness 0.15)) (justify left bottom))
    )
    (fp_text value "TP_1mm_SMD" (at 0 1.4) (layer "F.Fab") hide
        (effects (font (size 0.7 0.7) (thickness 0.15)) (justify left bottom))
    )
    (fp_text user "License: Apache-2.0" (at -0.5 5.2) (layer "F.Fab") hide
        (effects (font (size 0.7 0.7) (thickness 0.15)) (justify left bottom))
    )
    (fp_text user "Author: Antmicro" (at -0.5 4) (layer "F.Fab") hide
        (effects (font (size 0.7 0.7) (thickness 0.15)) (justify left bottom))
    )
    (fp_text user "${REFERENCE}" (at -0.5 2.8) (layer "F.Fab") hide
        (effects (font (size 0.7 0.7) (thickness 0.15)) (justify left bottom))
    )
    (pad "1" smd circle (at 0 0) (size 1 1) (layers "F.Cu" "F.Mask")
      (net 304 "VCC3V3") (pinfunction "1") (pintype "passive"))
  )
	(footprint "data-center-rdimm-ddr4-tester-footprints:C_0603_1608Metric" (layer "F.Cu")
    (at 116.661328 102.497157 180)
    (descr "Capacitor SMD 0603")
    (tags "capacitor 0603")
    (property "Author" "Antmicro")
    (property "Dielectric" "")
    (property "License" "Apache-2.0")
    (property "MPN" "C1608X5R1E106M080AC")
    (property "Manufacturer" "TDK")
    (property "Sheetfile" "supply.kicad_sch")
    (property "Sheetname" "Supply")
    (property "Val" "10u/25V")
    (property "Voltage" "")
    (property "ki_description" " ")
    (attr smd)
    (fp_text reference "C29" (at 1.241328 -1.062843 270) (layer "F.SilkS")
        (effects (font (size 0.7 0.7) (thickness 0.15)) (justify left bottom))
    )
    (fp_text value "C_10u_25V_0603" (at 0 1.6 180) (layer "F.Fab") hide
        (effects (font (size 0.7 0.7) (thickness 0.15)) (justify left bottom))
    )
    (fp_text user "License: Apache-2.0" (at -1.682 5.895 180) (layer "F.Fab") hide
        (effects (font (size 0.7 0.7) (thickness 0.15)) (justify left bottom))
    )
    (fp_text user "Author: Antmicro" (at -1.682 4.894 180) (layer "F.Fab") hide
        (effects (font (size 0.7 0.7) (thickness 0.15)) (justify left bottom))
    )
    (fp_text user "${REFERENCE}" (at -1.682 3.895 180) (layer "F.Fab") hide
        (effects (font (size 0.7 0.7) (thickness 0.15)) (justify left bottom))
    )
    (fp_line (start -0.3 -0.3) (end 0.3 -0.3)
      (stroke (width 0.15) (type solid)) (layer "F.SilkS"))
    (fp_line (start -0.3 0.3) (end 0.3 0.3)
      (stroke (width 0.15) (type solid)) (layer "F.SilkS"))
    (fp_rect (start -1.24 -0.7) (end 1.24 0.7)
      (stroke (width 0.05) (type solid)) (fill none) (layer "F.CrtYd"))
    (fp_rect (start -0.8 -0.4) (end 0.8 0.4)
      (stroke (width 0.15) (type solid)) (fill none) (layer "F.Fab"))
    (pad "1" smd roundrect (at -0.7 0 180) (size 0.6 0.8) (layers "F.Cu" "F.Paste" "F.Mask") (roundrect_rratio 0.2)
      (net 103 "VIN") (pintype "passive"))
    (pad "2" smd roundrect (at 0.7 0 180) (size 0.6 0.8) (layers "F.Cu" "F.Paste" "F.Mask") (roundrect_rratio 0.2)
      (net 9 "GND") (pintype "passive"))
  )
	(footprint "data-center-rdimm-ddr4-tester-footprints:C_0402_1005Metric" (layer "F.Cu")
    (at 110.286328 114.872157)
    (descr "Capacitor SMD 0402")
    (tags "capacitor SMD 0402")
    (property "Author" "Antmicro")
    (property "Dielectric" "X7R")
    (property "License" "Apache-2.0")
    (property "MPN" "GRM155R71H103KA88D")
    (property "Manufacturer" "Murata")
    (property "Sheetfile" "supply.kicad_sch")
    (property "Sheetname" "Supply")
    (property "Val" "10n")
    (property "Voltage" "50V")
    (property "ki_description" " ")
    (attr smd)
    (fp_text reference "C174" (at -1.446328 2.467843) (layer "F.SilkS")
        (effects (font (size 0.7 0.7) (thickness 0.15)) (justify left bottom))
    )
    (fp_text value "C_10n_0402" (at 0 1.4) (layer "F.Fab") hide
        (effects (font (size 0.7 0.7) (thickness 0.15)) (justify left bottom))
    )
    (fp_text user "${REFERENCE}" (at -0.932 3.168) (layer "F.Fab") hide
        (effects (font (size 0.7 0.7) (thickness 0.15)) (justify left bottom))
    )
    (fp_text user "License: Apache-2.0" (at -0.932 5.17) (layer "F.Fab") hide
        (effects (font (size 0.7 0.7) (thickness 0.15)) (justify left bottom))
    )
    (fp_text user "Author: Antmicro" (at -0.932 4.17) (layer "F.Fab") hide
        (effects (font (size 0.7 0.7) (thickness 0.15)) (justify left bottom))
    )
    (fp_rect (start -0.94 -0.47) (end 0.94 0.47)
      (stroke (width 0.05) (type solid)) (fill none) (layer "F.CrtYd"))
    (fp_rect (start -0.499 -0.249) (end 0.499 0.249)
      (stroke (width 0.15) (type solid)) (fill none) (layer "F.Fab"))
    (pad "1" smd roundrect (at -0.484 0) (size 0.59 0.64) (layers "F.Cu" "F.Paste" "F.Mask") (roundrect_rratio 0.25)
      (net 9 "GND") (pintype "passive"))
    (pad "2" smd roundrect (at 0.484 0) (size 0.59 0.64) (layers "F.Cu" "F.Paste" "F.Mask") (roundrect_rratio 0.25)
      (net 53 "Net-(IC1-SS{slash}TR)") (pintype "passive"))
  )
)
